#ISCELL
  mstr_misc dns *
  *
#ISCELL
  mstr_symbols cad_note *
  *
#ISCELL
  mstr_symbols design_note *
  *
#ISCELL
  mstr_symbols intel_corp_bpage *
  *
#CELL
  mstr_ttl ttl08 *
  page170_i10
#CELL
  mstr_ttl ttl08 *
  page170_i11
#CELL
  mstr_ttl ttl08 *
  page170_i12
#ISCELL
  mstr_standard offpage *
  page170_i15
#ISCELL
  mstr_standard offpage *
  page170_i16
#ISCELL
  mstr_standard offpage *
  page170_i17
#ISCELL
  mstr_standard offpage *
  page170_i18
#ISCELL
  mstr_standard offpage *
  page170_i19
#CELL
  mstr_discrete res *
  page170_i2
#CELL
  mstr_ttl ttl1g126_a *
  page170_i20
#ISCELL
  mstr_symbols p3v3_stby *
  page170_i3
#CELL
  dev_discrete cap_a *
  page170_i30
#ISCELL
  mstr_symbols gnd *
  page170_i31
#ISCELL
  mstr_symbols p3v3_stby *
  page170_i32
#CELL
  dev_discrete cap_a *
  page170_i33
#ISCELL
  mstr_symbols gnd *
  page170_i34
#ISCELL
  mstr_symbols p3v3_stby *
  page170_i35
#CELL
  mstr_ttl ttl1g126_a *
  page170_i38
#ISCELL
  mstr_symbols p3v3_stby *
  page170_i39
#CELL
  mstr_ttl ttl1g07_a *
  page170_i4
#CELL
  dev_discrete cap_a *
  page170_i40
#ISCELL
  mstr_symbols gnd *
  page170_i41
#CELL
  mstr_discrete cap *
  page170_i42
#ISCELL
  mstr_symbols gnd *
  page170_i43
#ISCELL
  mstr_standard offpage *
  page170_i44
#CELL
  mstr_ttl ttl1g07_a *
  page170_i46
#ISCELL
  mstr_standard offpage *
  page170_i47
#ISCELL
  mstr_symbols p3v3_stby *
  page170_i48
#CELL
  dev_discrete cap_a *
  page170_i49
#ISCELL
  mstr_standard offpage *
  page170_i5
#ISCELL
  mstr_symbols gnd *
  page170_i50
#CELL
  mstr_discrete res *
  page170_i51
#ISCELL
  mstr_symbols p3v3_stby *
  page170_i53
#CELL
  mstr_discrete res *
  page170_i54
#ISCELL
  mstr_symbols p3v3_stby *
  page170_i55
#CELL
  mstr_discrete res *
  page170_i56
#CELL
  mstr_discrete fet_n *
  page170_i58
#ISCELL
  mstr_standard offpage *
  page170_i59
#ISCELL
  mstr_symbols p3v3_stby *
  page170_i6
#ISCELL
  mstr_symbols gnd *
  page170_i60
#CELL
  mstr_discrete res *
  page170_i61
#ISCELL
  mstr_symbols p3v3_stby *
  page170_i62
#CELL
  mstr_discrete res *
  page170_i63
#ISCELL
  mstr_symbols gnd *
  page170_i64
#CELL
  mstr_discrete res *
  page170_i65
#ISCELL
  mstr_symbols p3v3_stby *
  page170_i66
#CELL
  mstr_discrete fet_n *
  page170_i67
#ISCELL
  mstr_symbols gnd *
  page170_i68
#ISCELL
  mstr_standard offpage *
  page170_i69
#ISCELL
  mstr_symbols gnd *
  page170_i7
#ISCELL
  mstr_symbols p3v3_stby *
  page170_i70
#CELL
  mstr_discrete res *
  page170_i71
#ISCELL
  mstr_symbols p3v3_stby *
  page170_i72
#CELL
  mstr_discrete res *
  page170_i73
#CELL
  mstr_discrete res *
  page170_i74
#CELL
  mstr_discrete res *
  page170_i75
#CELL
  dev_discrete cap_a *
  page170_i8
